(kicad_pcb
	(version 20260206)
	(generator "pcbnew")
	(generator_version "10.0")
	(general
		(thickness 1.6)
		(legacy_teardrops no)
	)
	(paper "A4")
	(title_block
		(title "timecard-production-celestica-r4006 — R4006-B0001-02_R01.brd")
		(comment 1 "Time Appliance Project (Time Card) / footprints 995-999 of 1113")
	)
	(layers
		(0 "F.Cu" signal "TOP")
		(4 "In1.Cu" signal "L02_GND1")
		(6 "In2.Cu" signal "L03_SIG1")
		(8 "In3.Cu" signal "L04_GND2")
		(10 "In4.Cu" signal "L05_VCC1")
		(12 "In5.Cu" signal "L06_VCC2")
		(14 "In6.Cu" signal "L07_GND3")
		(16 "In7.Cu" signal "L08_SIG2")
		(18 "In8.Cu" signal "L09_GND4")
		(2 "B.Cu" signal "BOTTOM")
		(9 "F.Adhes" user "F.Adhesive")
		(11 "B.Adhes" user "B.Adhesive")
		(13 "F.Paste" user "Package Geometry/Pastemask Top")
		(15 "B.Paste" user "Package Geometry/Pastemask Bottom")
		(5 "F.SilkS" user "Ref Des/Silkscreen Top")
		(7 "B.SilkS" user "Ref Des/Silkscreen Bottom")
		(1 "F.Mask" user "Board Geometry/Soldermask Top")
		(3 "B.Mask" user "Board Geometry/Soldermask Bottom")
		(17 "Dwgs.User" user "User.Drawings")
		(19 "Cmts.User" user "User.Comments")
		(21 "Eco1.User" user "User.Eco1")
		(23 "Eco2.User" user "User.Eco2")
		(25 "Edge.Cuts" user "Board Geometry/Outline")
		(27 "Margin" user)
		(31 "F.CrtYd" user "Package Geometry/Place Bound Top")
		(29 "B.CrtYd" user "Package Geometry/Place Bound Bottom")
		(35 "F.Fab" user "Ref Des/Assembly Top")
		(33 "B.Fab" user "Ref Des/Assembly Bottom")
	)
	(footprint ""
		(layer "B.Cu")
		(at 17.78 -86.487 90)
		(property "Reference" "C94"
			(at 0.127 1.23063 270)
			(unlocked yes)
			(layer "B.SilkS")
			(effects
				(font
					(size 0.7874 0.5842)
					(thickness 0.1524)
				)
				(justify mirror)
			)
		)
		(property "Value" "VAL*"
			(at -0.0762 2.067306 90)
			(unlocked yes)
			(layer "B.Fab")
			(hide yes)
			(effects
				(font
					(size 0.7874 0.5842)
					(thickness 0.1524)
				)
				(justify mirror)
			)
		)
		(property "Tolerance" "TOL*"
			(at -0.0762 3.032506 90)
			(unlocked yes)
			(layer "Cmts.User")
			(hide yes)
			(effects
				(font
					(size 0.7874 0.5842)
					(thickness 0.1524)
				)
				(justify mirror)
			)
		)
		(property "User Part Number" "PARTNUM*"
			(at -0.1016 4.023106 90)
			(unlocked yes)
			(layer "Cmts.User")
			(hide yes)
			(effects
				(font
					(size 0.7874 0.5842)
					(thickness 0.1524)
				)
				(justify mirror)
			)
		)
		(property "Device Type" "CAPACITOR-G105-0B104-EK,0.1UF,A"
			(at -0.0508 1.127506 90)
			(unlocked yes)
			(layer "B.Fab")
			(hide yes)
			(effects
				(font
					(size 0.7874 0.5842)
					(thickness 0.1524)
				)
				(justify mirror)
			)
		)
		(duplicate_pad_numbers_are_jumpers no)
		(fp_line
			(start 1.143 -0.5588)
			(end 1.143 0.5588)
			(stroke
				(width 0.1)
				(type default)
			)
			(layer "B.SilkS")
		)
		(fp_line
			(start -1.143 -0.5588)
			(end 1.143 -0.5588)
			(stroke
				(width 0.1)
				(type default)
			)
			(layer "B.SilkS")
		)
		(fp_line
			(start 1.143 0.5588)
			(end -1.143 0.5588)
			(stroke
				(width 0.1)
				(type default)
			)
			(layer "B.SilkS")
		)
		(fp_line
			(start -1.143 0.5588)
			(end -1.143 -0.5588)
			(stroke
				(width 0.1)
				(type default)
			)
			(layer "B.SilkS")
		)
		(fp_poly
			(pts
				(xy 1.143 0.5588) (xy -1.143 0.5588) (xy -1.143 -0.5588) (xy 1.143 -0.5588)
			)
			(stroke
				(width 0)
				(type default)
			)
			(fill no)
			(layer "B.CrtYd")
		)
		(fp_line
			(start 0.508 -0.3048)
			(end 0.508 0.3048)
			(stroke
				(width 0.1)
				(type default)
			)
			(layer "B.Fab")
		)
		(fp_line
			(start -0.508 -0.3048)
			(end 0.508 -0.3048)
			(stroke
				(width 0.1)
				(type default)
			)
			(layer "B.Fab")
		)
		(fp_line
			(start 0.508 0.3048)
			(end -0.508 0.3048)
			(stroke
				(width 0.1)
				(type default)
			)
			(layer "B.Fab")
		)
		(fp_line
			(start -0.508 0.3048)
			(end -0.508 -0.3048)
			(stroke
				(width 0.1)
				(type default)
			)
			(layer "B.Fab")
		)
		(pad "1" smd rect
			(at 0.5334 0 270)
			(size 0.7112 0.6096)
			(layers "B.Cu" "B.Mask" "B.Paste")
			(net "XP5R0V_FT4232")
		)
		(pad "2" smd rect
			(at -0.5334 0 270)
			(size 0.7112 0.6096)
			(layers "B.Cu" "B.Mask" "B.Paste")
			(net "SG")
		)
		(zone
			(layer "B.Cu")
			(hatch none 0.5)
			(connect_pads
				(clearance 0)
			)
			(min_thickness 0.25)
			(keepout
				(tracks not_allowed)
				(vias allowed)
				(pads allowed)
				(copperpour not_allowed)
				(footprints allowed)
			)
			(placement
				(enabled no)
				(sheetname "")
			)
			(fill
				(thermal_gap 0.5)
				(thermal_bridge_width 0.5)
				(island_removal_mode 0)
			)
			(polygon
				(pts
					(xy 18.0848 -86.5632) (xy 17.4752 -86.5632) (xy 17.4752 -86.4108) (xy 18.0848 -86.4108)
				)
			)
		)
		(zone
			(layer "B.Cu")
			(hatch none 0.5)
			(connect_pads
				(clearance 0)
			)
			(min_thickness 0.25)
			(keepout
				(tracks allowed)
				(vias not_allowed)
				(pads allowed)
				(copperpour not_allowed)
				(footprints allowed)
			)
			(placement
				(enabled no)
				(sheetname "")
			)
			(fill
				(thermal_gap 0.5)
				(thermal_bridge_width 0.5)
				(island_removal_mode 0)
			)
			(polygon
				(pts
					(xy 18.0848 -86.5632) (xy 17.4752 -86.5632) (xy 17.4752 -86.4108) (xy 18.0848 -86.4108)
				)
			)
		)
	)
	(footprint ""
		(layer "B.Cu")
		(at 89.9922 -98.7298)
		(property "Reference" "R54"
			(at 3.683 0.03937 0)
			(unlocked yes)
			(layer "B.SilkS")
			(effects
				(font
					(size 0.7874 0.5842)
					(thickness 0.1524)
				)
				(justify mirror)
			)
		)
		(property "Value" "VAL*"
			(at 0.0254 2.524506 0)
			(unlocked yes)
			(layer "B.Fab")
			(hide yes)
			(effects
				(font
					(size 0.7874 0.5842)
					(thickness 0.1524)
				)
				(justify mirror)
			)
		)
		(property "Tolerance" "TOL*"
			(at 0.0254 3.464306 0)
			(unlocked yes)
			(layer "Cmts.User")
			(hide yes)
			(effects
				(font
					(size 0.7874 0.5842)
					(thickness 0.1524)
				)
				(justify mirror)
			)
		)
		(property "User Part Number" "PARTNUM*"
			(at 0.0254 4.505706 0)
			(unlocked yes)
			(layer "Cmts.User")
			(hide yes)
			(effects
				(font
					(size 0.7874 0.5842)
					(thickness 0.1524)
				)
				(justify mirror)
			)
		)
		(property "Device Type" "RESISTOR-G156-100R0-J0,0OHM,-"
			(at 0 1.610106 0)
			(unlocked yes)
			(layer "B.Fab")
			(hide yes)
			(effects
				(font
					(size 0.7874 0.5842)
					(thickness 0.1524)
				)
				(justify mirror)
			)
		)
		(duplicate_pad_numbers_are_jumpers no)
		(fp_line
			(start -1.3208 -0.7112)
			(end -1.3208 0.7112)
			(stroke
				(width 0.1)
				(type default)
			)
			(layer "B.SilkS")
		)
		(fp_line
			(start -1.3208 0.7112)
			(end 1.3208 0.7112)
			(stroke
				(width 0.1)
				(type default)
			)
			(layer "B.SilkS")
		)
		(fp_line
			(start 1.3208 -0.7112)
			(end -1.3208 -0.7112)
			(stroke
				(width 0.1)
				(type default)
			)
			(layer "B.SilkS")
		)
		(fp_line
			(start 1.3208 0.7112)
			(end 1.3208 -0.7112)
			(stroke
				(width 0.1)
				(type default)
			)
			(layer "B.SilkS")
		)
		(fp_rect
			(start -1.3208 0.7112)
			(end 1.3208 -0.7112)
			(stroke
				(width 0)
				(type default)
			)
			(fill no)
			(layer "B.CrtYd")
		)
		(fp_line
			(start -0.8128 -0.4572)
			(end -0.8128 0.4572)
			(stroke
				(width 0.1)
				(type default)
			)
			(layer "B.Fab")
		)
		(fp_line
			(start -0.8128 0.4572)
			(end 0.8128 0.4572)
			(stroke
				(width 0.1)
				(type default)
			)
			(layer "B.Fab")
		)
		(fp_line
			(start 0.8128 -0.4572)
			(end -0.8128 -0.4572)
			(stroke
				(width 0.1)
				(type default)
			)
			(layer "B.Fab")
		)
		(fp_line
			(start 0.8128 0.4572)
			(end 0.8128 -0.4572)
			(stroke
				(width 0.1)
				(type default)
			)
			(layer "B.Fab")
		)
		(pad "1" smd rect
			(at 0.6858 0 180)
			(size 0.762 0.8636)
			(layers "B.Cu" "B.Mask" "B.Paste")
			(net "XP3R3V_AGND")
		)
		(pad "2" smd rect
			(at -0.6858 0 180)
			(size 0.762 0.8636)
			(layers "B.Cu" "B.Mask" "B.Paste")
			(net "XP3R3V_FB_R_TO_AGND")
		)
		(zone
			(layer "B.Cu")
			(hatch none 0.5)
			(connect_pads
				(clearance 0)
			)
			(min_thickness 0.25)
			(keepout
				(tracks allowed)
				(vias not_allowed)
				(pads allowed)
				(copperpour not_allowed)
				(footprints allowed)
			)
			(placement
				(enabled no)
				(sheetname "")
			)
			(fill
				(thermal_gap 0.5)
				(thermal_bridge_width 0.5)
				(island_removal_mode 0)
			)
			(polygon
				(pts
					(xy 89.8398 -98.2726) (xy 90.1446 -98.2726) (xy 90.1446 -99.187) (xy 89.8398 -99.187)
				)
			)
		)
	)
	(footprint ""
		(layer "B.Cu")
		(at 57.404 -16.51 -90)
		(property "Reference" "L21"
			(at -3.1115 -0.08763 270)
			(unlocked yes)
			(layer "B.SilkS")
			(effects
				(font
					(size 0.7874 0.5842)
					(thickness 0.1524)
				)
				(justify left mirror)
			)
		)
		(property "Value" "VAL*"
			(at 0.9398 3.70967 270)
			(unlocked yes)
			(layer "B.Fab")
			(hide yes)
			(effects
				(font
					(size 0.7874 0.5842)
					(thickness 0.1524)
				)
				(justify left mirror)
			)
		)
		(property "Device Type" "FERRITEBEAD-G191-10101-01,26OHA"
			(at 0.9906 1.22047 270)
			(unlocked yes)
			(layer "B.Fab")
			(hide yes)
			(effects
				(font
					(size 0.7874 0.5842)
					(thickness 0.1524)
				)
				(justify left mirror)
			)
		)
		(property "User Part Number" "PARTNUM*"
			(at 2.54 2.46507 270)
			(unlocked yes)
			(layer "Cmts.User")
			(hide yes)
			(effects
				(font
					(size 0.7874 0.5842)
					(thickness 0.1524)
				)
				(justify left mirror)
			)
		)
		(property "Tolerance" "TOL*"
			(at 0.9906 5.00507 270)
			(unlocked yes)
			(layer "Cmts.User")
			(hide yes)
			(effects
				(font
					(size 0.7874 0.5842)
					(thickness 0.1524)
				)
				(justify left mirror)
			)
		)
		(duplicate_pad_numbers_are_jumpers no)
		(fp_line
			(start -1.3208 0.7112)
			(end 1.3208 0.7112)
			(stroke
				(width 0.1)
				(type default)
			)
			(layer "B.SilkS")
		)
		(fp_line
			(start 1.3208 0.7112)
			(end 1.3208 -0.7112)
			(stroke
				(width 0.1)
				(type default)
			)
			(layer "B.SilkS")
		)
		(fp_line
			(start -1.3208 -0.7112)
			(end -1.3208 0.7112)
			(stroke
				(width 0.1)
				(type default)
			)
			(layer "B.SilkS")
		)
		(fp_line
			(start 1.3208 -0.7112)
			(end -1.3208 -0.7112)
			(stroke
				(width 0.1)
				(type default)
			)
			(layer "B.SilkS")
		)
		(fp_rect
			(start 1.3208 0.7112)
			(end -1.3208 -0.7112)
			(stroke
				(width 0)
				(type default)
			)
			(fill no)
			(layer "B.CrtYd")
		)
		(fp_line
			(start -0.8128 0.4572)
			(end 0.8128 0.4572)
			(stroke
				(width 0.1)
				(type default)
			)
			(layer "B.Fab")
		)
		(fp_line
			(start 0.8128 0.4572)
			(end 0.8128 -0.4572)
			(stroke
				(width 0.1)
				(type default)
			)
			(layer "B.Fab")
		)
		(fp_line
			(start -0.8128 -0.4572)
			(end -0.8128 0.4572)
			(stroke
				(width 0.1)
				(type default)
			)
			(layer "B.Fab")
		)
		(fp_line
			(start 0.8128 -0.4572)
			(end -0.8128 -0.4572)
			(stroke
				(width 0.1)
				(type default)
			)
			(layer "B.Fab")
		)
		(pad "1" smd rect
			(at 0.6858 0 90)
			(size 0.762 0.8636)
			(layers "B.Cu" "B.Mask" "B.Paste")
			(net "XP3R3V_PCIE")
		)
		(pad "2" smd rect
			(at -0.6858 0 90)
			(size 0.762 0.8636)
			(layers "B.Cu" "B.Mask" "B.Paste")
			(net "XP3R3V")
		)
		(zone
			(layer "B.Cu")
			(hatch none 0.5)
			(connect_pads
				(clearance 0)
			)
			(min_thickness 0.25)
			(keepout
				(tracks allowed)
				(vias not_allowed)
				(pads allowed)
				(copperpour not_allowed)
				(footprints allowed)
			)
			(placement
				(enabled no)
				(sheetname "")
			)
			(fill
				(thermal_gap 0.5)
				(thermal_bridge_width 0.5)
				(island_removal_mode 0)
			)
			(polygon
				(pts
					(xy 56.9468 -16.3576) (xy 57.8612 -16.3576) (xy 57.8612 -16.6624) (xy 56.9468 -16.6624)
				)
			)
		)
		(zone
			(layer "B.Cu")
			(hatch none 0.5)
			(connect_pads
				(clearance 0)
			)
			(min_thickness 0.25)
			(keepout
				(tracks not_allowed)
				(vias allowed)
				(pads allowed)
				(copperpour not_allowed)
				(footprints allowed)
			)
			(placement
				(enabled no)
				(sheetname "")
			)
			(fill
				(thermal_gap 0.5)
				(thermal_bridge_width 0.5)
				(island_removal_mode 0)
			)
			(polygon
				(pts
					(xy 56.9468 -16.3576) (xy 57.8612 -16.3576) (xy 57.8612 -16.6624) (xy 56.9468 -16.6624)
				)
			)
		)
	)
	(footprint ""
		(layer "B.Cu")
		(at 76.708 -52.07 180)
		(property "Reference" "C66"
			(at -3.175 0.21463 0)
			(unlocked yes)
			(layer "B.SilkS")
			(effects
				(font
					(size 0.7874 0.5842)
					(thickness 0.1524)
				)
				(justify mirror)
			)
		)
		(property "Value" "VAL*"
			(at -0.0762 2.067306 180)
			(unlocked yes)
			(layer "B.Fab")
			(hide yes)
			(effects
				(font
					(size 0.7874 0.5842)
					(thickness 0.1524)
				)
				(justify mirror)
			)
		)
		(property "Tolerance" "TOL*"
			(at -0.0762 3.032506 180)
			(unlocked yes)
			(layer "Cmts.User")
			(hide yes)
			(effects
				(font
					(size 0.7874 0.5842)
					(thickness 0.1524)
				)
				(justify mirror)
			)
		)
		(property "User Part Number" "PARTNUM*"
			(at -0.1016 4.023106 180)
			(unlocked yes)
			(layer "Cmts.User")
			(hide yes)
			(effects
				(font
					(size 0.7874 0.5842)
					(thickness 0.1524)
				)
				(justify mirror)
			)
		)
		(property "Device Type" "CAPACITOR-G105-0B104-EK,0.1UF,A"
			(at -0.0508 1.127506 180)
			(unlocked yes)
			(layer "B.Fab")
			(hide yes)
			(effects
				(font
					(size 0.7874 0.5842)
					(thickness 0.1524)
				)
				(justify mirror)
			)
		)
		(duplicate_pad_numbers_are_jumpers no)
		(fp_line
			(start 1.143 0.5588)
			(end -1.143 0.5588)
			(stroke
				(width 0.1)
				(type default)
			)
			(layer "B.SilkS")
		)
		(fp_line
			(start 1.143 -0.5588)
			(end 1.143 0.5588)
			(stroke
				(width 0.1)
				(type default)
			)
			(layer "B.SilkS")
		)
		(fp_line
			(start -1.143 0.5588)
			(end -1.143 -0.5588)
			(stroke
				(width 0.1)
				(type default)
			)
			(layer "B.SilkS")
		)
		(fp_line
			(start -1.143 -0.5588)
			(end 1.143 -0.5588)
			(stroke
				(width 0.1)
				(type default)
			)
			(layer "B.SilkS")
		)
		(fp_rect
			(start 1.143 0.5588)
			(end -1.143 -0.5588)
			(stroke
				(width 0)
				(type default)
			)
			(fill no)
			(layer "B.CrtYd")
		)
		(fp_line
			(start 0.508 0.3048)
			(end -0.508 0.3048)
			(stroke
				(width 0.1)
				(type default)
			)
			(layer "B.Fab")
		)
		(fp_line
			(start 0.508 -0.3048)
			(end 0.508 0.3048)
			(stroke
				(width 0.1)
				(type default)
			)
			(layer "B.Fab")
		)
		(fp_line
			(start -0.508 0.3048)
			(end -0.508 -0.3048)
			(stroke
				(width 0.1)
				(type default)
			)
			(layer "B.Fab")
		)
		(fp_line
			(start -0.508 -0.3048)
			(end 0.508 -0.3048)
			(stroke
				(width 0.1)
				(type default)
			)
			(layer "B.Fab")
		)
		(pad "1" smd rect
			(at 0.5334 0)
			(size 0.7112 0.6096)
			(layers "B.Cu" "B.Mask" "B.Paste")
			(net "XP5R0V_MAC_USB")
		)
		(pad "2" smd rect
			(at -0.5334 0)
			(size 0.7112 0.6096)
			(layers "B.Cu" "B.Mask" "B.Paste")
			(net "SG")
		)
		(zone
			(layer "B.Cu")
			(hatch none 0.5)
			(connect_pads
				(clearance 0)
			)
			(min_thickness 0.25)
			(keepout
				(tracks allowed)
				(vias not_allowed)
				(pads allowed)
				(copperpour not_allowed)
				(footprints allowed)
			)
			(placement
				(enabled no)
				(sheetname "")
			)
			(fill
				(thermal_gap 0.5)
				(thermal_bridge_width 0.5)
				(island_removal_mode 0)
			)
			(polygon
				(pts
					(xy 76.6318 -52.3748) (xy 76.6318 -51.7652) (xy 76.7842 -51.7652) (xy 76.7842 -52.3748)
				)
			)
		)
	)
	(footprint ""
		(layer "B.Cu")
		(at 84.709 -64.3128 90)
		(property "Reference" "R80"
			(at -0.3048 1.10363 270)
			(unlocked yes)
			(layer "B.SilkS")
			(effects
				(font
					(size 0.7874 0.5842)
					(thickness 0.1524)
				)
				(justify mirror)
			)
		)
		(property "Value" "VAL*"
			(at -0.02032 2.13233 90)
			(unlocked yes)
			(layer "B.Fab")
			(hide yes)
			(effects
				(font
					(size 0.7874 0.5842)
					(thickness 0.1524)
				)
				(justify mirror)
			)
		)
		(property "Device Type" "RESISTOR-G155-133R0-01,33OHM,1%"
			(at -0.008382 1.210564 90)
			(unlocked yes)
			(layer "B.Fab")
			(hide yes)
			(effects
				(font
					(size 0.7874 0.5842)
					(thickness 0.1524)
				)
				(justify mirror)
			)
		)
		(property "User Part Number" "PARTNUM*"
			(at -0.02032 4.024884 90)
			(unlocked yes)
			(layer "Cmts.User")
			(hide yes)
			(effects
				(font
					(size 0.7874 0.5842)
					(thickness 0.1524)
				)
				(justify mirror)
			)
		)
		(property "Tolerance" "TOL*"
			(at -0.044704 3.05435 90)
			(unlocked yes)
			(layer "Cmts.User")
			(hide yes)
			(effects
				(font
					(size 0.7874 0.5842)
					(thickness 0.1524)
				)
				(justify mirror)
			)
		)
		(duplicate_pad_numbers_are_jumpers no)
		(fp_line
			(start 1.143 -0.5588)
			(end 1.143 0.5588)
			(stroke
				(width 0.1)
				(type default)
			)
			(layer "B.SilkS")
		)
		(fp_line
			(start -1.143 -0.5588)
			(end 1.143 -0.5588)
			(stroke
				(width 0.1)
				(type default)
			)
			(layer "B.SilkS")
		)
		(fp_line
			(start 1.143 0.5588)
			(end -1.143 0.5588)
			(stroke
				(width 0.1)
				(type default)
			)
			(layer "B.SilkS")
		)
		(fp_line
			(start -1.143 0.5588)
			(end -1.143 -0.5588)
			(stroke
				(width 0.1)
				(type default)
			)
			(layer "B.SilkS")
		)
		(fp_rect
			(start -1.143 -0.5588)
			(end 1.143 0.5588)
			(stroke
				(width 0)
				(type default)
			)
			(fill no)
			(layer "B.CrtYd")
		)
		(fp_line
			(start 0.508 -0.3048)
			(end 0.508 0.3048)
			(stroke
				(width 0.1)
				(type default)
			)
			(layer "B.Fab")
		)
		(fp_line
			(start -0.508 -0.3048)
			(end 0.508 -0.3048)
			(stroke
				(width 0.1)
				(type default)
			)
			(layer "B.Fab")
		)
		(fp_line
			(start 0.508 0.3048)
			(end -0.508 0.3048)
			(stroke
				(width 0.1)
				(type default)
			)
			(layer "B.Fab")
		)
		(fp_line
			(start -0.508 0.3048)
			(end -0.508 -0.3048)
			(stroke
				(width 0.1)
				(type default)
			)
			(layer "B.Fab")
		)
		(pad "1" smd rect
			(at 0.5334 0 270)
			(size 0.7112 0.6096)
			(layers "B.Cu" "B.Mask" "B.Paste")
			(net "FPGA_OUT_BNO080_BOOT_N")
		)
		(pad "2" smd rect
			(at -0.5334 0 270)
			(size 0.7112 0.6096)
			(layers "B.Cu" "B.Mask" "B.Paste")
			(net "R_BNO080_BOOT_N")
		)
		(zone
			(layer "B.Cu")
			(hatch none 0.5)
			(connect_pads
				(clearance 0)
			)
			(min_thickness 0.25)
			(keepout
				(tracks allowed)
				(vias not_allowed)
				(pads allowed)
				(copperpour not_allowed)
				(footprints allowed)
			)
			(placement
				(enabled no)
				(sheetname "")
			)
			(fill
				(thermal_gap 0.5)
				(thermal_bridge_width 0.5)
				(island_removal_mode 0)
			)
			(polygon
				(pts
					(xy 84.4042 -64.2366) (xy 85.0138 -64.2366) (xy 85.0138 -64.389) (xy 84.4042 -64.389)
				)
			)
		)
	)
)
